(kicad_pcb
	(version 20260206)
	(generator "pcbnew")
	(generator_version "10.0")
	(general
		(thickness 1.6)
		(legacy_teardrops no)
	)
	(paper "A4")
	(title_block
		(title "03242023_DA0F0TMBIJ0_F0T_Motherboard_J_brd_V01_OCP.brd")
		(comment 1 "Grand Teton / footprints 5812-5817 of 6105")
	)
	(layers
		(0 "F.Cu" signal "TOP")
		(4 "In1.Cu" signal "GND")
		(6 "In2.Cu" signal "IN1")
		(8 "In3.Cu" signal "GND1")
		(10 "In4.Cu" signal "IN2")
		(12 "In5.Cu" signal "GND2")
		(14 "In6.Cu" signal "IN3")
		(16 "In7.Cu" signal "GND3")
		(18 "In8.Cu" signal "VCC")
		(20 "In9.Cu" signal "VCC1")
		(22 "In10.Cu" signal "GND4")
		(24 "In11.Cu" signal "IN4")
		(26 "In12.Cu" signal "GND5")
		(28 "In13.Cu" signal "IN5")
		(30 "In14.Cu" signal "GND6")
		(32 "In15.Cu" signal "IN6")
		(34 "In16.Cu" signal "GND7")
		(2 "B.Cu" signal "BOTTOM")
		(9 "F.Adhes" user "F.Adhesive")
		(11 "B.Adhes" user "B.Adhesive")
		(13 "F.Paste" user "Package Geometry/Pastemask Top")
		(15 "B.Paste" user "Package Geometry/Pastemask Bottom")
		(5 "F.SilkS" user "Ref Des/Silkscreen Top")
		(7 "B.SilkS" user "Ref Des/Silkscreen Bottom")
		(1 "F.Mask" user "Board Geometry/Soldermask Top")
		(3 "B.Mask" user "Board Geometry/Soldermask Bottom")
		(17 "Dwgs.User" user "User.Drawings")
		(19 "Cmts.User" user "User.Comments")
		(21 "Eco1.User" user "User.Eco1")
		(23 "Eco2.User" user "User.Eco2")
		(25 "Edge.Cuts" user "Board Geometry/Outline")
		(27 "Margin" user)
		(31 "F.CrtYd" user "Package Geometry/Place Bound Top")
		(29 "B.CrtYd" user "Package Geometry/Place Bound Bottom")
		(35 "F.Fab" user "Ref Des/Assembly Top")
		(33 "B.Fab" user "Ref Des/Assembly Bottom")
	)
	(footprint ""
		(layer "B.Cu")
		(at 321.001898 -186.43981 90)
		(property "Reference" "R336"
			(at 0 0 90)
			(layer "B.SilkS")
			(hide yes)
			(effects
				(font
					(size 1.27 1.27)
				)
				(justify mirror)
			)
		)
		(property "Value" ""
			(at 0 0 90)
			(layer "B.Fab")
			(effects
				(font
					(size 1.27 1.27)
				)
				(justify mirror)
			)
		)
		(duplicate_pad_numbers_are_jumpers no)
		(fp_line
			(start 0.7874 -0.4064)
			(end -0.7874 -0.4064)
			(stroke
				(width 0.1524)
				(type default)
			)
			(layer "B.SilkS")
		)
		(fp_line
			(start -0.7874 -0.4064)
			(end -0.7874 0.4064)
			(stroke
				(width 0.1524)
				(type default)
			)
			(layer "B.SilkS")
		)
		(fp_line
			(start 0.7874 0.4064)
			(end 0.7874 -0.4064)
			(stroke
				(width 0.1524)
				(type default)
			)
			(layer "B.SilkS")
		)
		(fp_line
			(start -0.7874 0.4064)
			(end 0.7874 0.4064)
			(stroke
				(width 0.1524)
				(type default)
			)
			(layer "B.SilkS")
		)
		(fp_line
			(start 0.67945 -0.305054)
			(end 0.12065 -0.305054)
			(stroke
				(width 0.1)
				(type default)
			)
			(layer "B.Fab")
		)
		(fp_line
			(start 0.12065 -0.305054)
			(end 0.12065 -0.2794)
			(stroke
				(width 0.1)
				(type default)
			)
			(layer "B.Fab")
		)
		(fp_line
			(start -0.12065 -0.3048)
			(end -0.67945 -0.3048)
			(stroke
				(width 0.1)
				(type default)
			)
			(layer "B.Fab")
		)
		(fp_line
			(start -0.67945 -0.3048)
			(end -0.67945 0.3048)
			(stroke
				(width 0.1)
				(type default)
			)
			(layer "B.Fab")
		)
		(fp_line
			(start 0.12065 -0.2794)
			(end -0.12065 -0.2794)
			(stroke
				(width 0.1)
				(type default)
			)
			(layer "B.Fab")
		)
		(fp_line
			(start -0.12065 -0.2794)
			(end -0.12065 -0.3048)
			(stroke
				(width 0.1)
				(type default)
			)
			(layer "B.Fab")
		)
		(fp_line
			(start 0.12065 0.2794)
			(end 0.12065 0.3048)
			(stroke
				(width 0.1)
				(type default)
			)
			(layer "B.Fab")
		)
		(fp_line
			(start -0.120396 0.2794)
			(end 0.12065 0.2794)
			(stroke
				(width 0.1)
				(type default)
			)
			(layer "B.Fab")
		)
		(fp_line
			(start 0.67945 0.3048)
			(end 0.67945 -0.305054)
			(stroke
				(width 0.1)
				(type default)
			)
			(layer "B.Fab")
		)
		(fp_line
			(start 0.12065 0.3048)
			(end 0.67945 0.3048)
			(stroke
				(width 0.1)
				(type default)
			)
			(layer "B.Fab")
		)
		(fp_line
			(start -0.120396 0.3048)
			(end -0.120396 0.2794)
			(stroke
				(width 0.1)
				(type default)
			)
			(layer "B.Fab")
		)
		(fp_line
			(start -0.67945 0.3048)
			(end -0.120396 0.3048)
			(stroke
				(width 0.1)
				(type default)
			)
			(layer "B.Fab")
		)
		(pad "1" smd circle
			(at 0.40005 0 270)
			(size 0 0)
			(layers "B.Cu" "B.Mask" "B.Paste")
			(net "H_CPU0_ERR0_LVC1_R_N")
		)
		(pad "2" smd circle
			(at -0.40005 0 270)
			(size 0 0)
			(layers "B.Cu" "B.Mask" "B.Paste")
			(net "H_CPU_ERR0_LVC1_R_N")
		)
	)
	(footprint ""
		(layer "B.Cu")
		(at 17.725136 -191.700404)
		(property "Reference" "R964"
			(at 0 0 0)
			(layer "B.SilkS")
			(hide yes)
			(effects
				(font
					(size 1.27 1.27)
				)
				(justify mirror)
			)
		)
		(property "Value" ""
			(at 0 0 0)
			(layer "B.Fab")
			(effects
				(font
					(size 1.27 1.27)
				)
				(justify mirror)
			)
		)
		(duplicate_pad_numbers_are_jumpers no)
		(fp_line
			(start -0.7874 -0.4064)
			(end -0.7874 0.4064)
			(stroke
				(width 0.1524)
				(type default)
			)
			(layer "B.SilkS")
		)
		(fp_line
			(start -0.7874 0.4064)
			(end 0.7874 0.4064)
			(stroke
				(width 0.1524)
				(type default)
			)
			(layer "B.SilkS")
		)
		(fp_line
			(start 0.7874 -0.4064)
			(end -0.7874 -0.4064)
			(stroke
				(width 0.1524)
				(type default)
			)
			(layer "B.SilkS")
		)
		(fp_line
			(start 0.7874 0.4064)
			(end 0.7874 -0.4064)
			(stroke
				(width 0.1524)
				(type default)
			)
			(layer "B.SilkS")
		)
		(fp_line
			(start -0.67945 -0.3048)
			(end -0.67945 0.3048)
			(stroke
				(width 0.1)
				(type default)
			)
			(layer "B.Fab")
		)
		(fp_line
			(start -0.67945 0.3048)
			(end -0.120396 0.3048)
			(stroke
				(width 0.1)
				(type default)
			)
			(layer "B.Fab")
		)
		(fp_line
			(start -0.12065 -0.3048)
			(end -0.67945 -0.3048)
			(stroke
				(width 0.1)
				(type default)
			)
			(layer "B.Fab")
		)
		(fp_line
			(start -0.12065 -0.2794)
			(end -0.12065 -0.3048)
			(stroke
				(width 0.1)
				(type default)
			)
			(layer "B.Fab")
		)
		(fp_line
			(start -0.120396 0.2794)
			(end 0.12065 0.2794)
			(stroke
				(width 0.1)
				(type default)
			)
			(layer "B.Fab")
		)
		(fp_line
			(start -0.120396 0.3048)
			(end -0.120396 0.2794)
			(stroke
				(width 0.1)
				(type default)
			)
			(layer "B.Fab")
		)
		(fp_line
			(start 0.12065 -0.305054)
			(end 0.12065 -0.2794)
			(stroke
				(width 0.1)
				(type default)
			)
			(layer "B.Fab")
		)
		(fp_line
			(start 0.12065 -0.2794)
			(end -0.12065 -0.2794)
			(stroke
				(width 0.1)
				(type default)
			)
			(layer "B.Fab")
		)
		(fp_line
			(start 0.12065 0.2794)
			(end 0.12065 0.3048)
			(stroke
				(width 0.1)
				(type default)
			)
			(layer "B.Fab")
		)
		(fp_line
			(start 0.12065 0.3048)
			(end 0.67945 0.3048)
			(stroke
				(width 0.1)
				(type default)
			)
			(layer "B.Fab")
		)
		(fp_line
			(start 0.67945 -0.305054)
			(end 0.12065 -0.305054)
			(stroke
				(width 0.1)
				(type default)
			)
			(layer "B.Fab")
		)
		(fp_line
			(start 0.67945 0.3048)
			(end 0.67945 -0.305054)
			(stroke
				(width 0.1)
				(type default)
			)
			(layer "B.Fab")
		)
		(pad "1" smd circle
			(at 0.40005 0 180)
			(size 0 0)
			(layers "B.Cu" "B.Mask" "B.Paste")
			(net "PVNN_TERM_CPU1")
		)
		(pad "2" smd circle
			(at -0.40005 0 180)
			(size 0 0)
			(layers "B.Cu" "B.Mask" "B.Paste")
			(net "SMB_PEHPCPU1_GTL_R_SDA")
		)
	)
	(footprint ""
		(layer "B.Cu")
		(at 173.377352 -22.564598 90)
		(property "Reference" "R1763"
			(at 0 0 90)
			(layer "B.SilkS")
			(hide yes)
			(effects
				(font
					(size 1.27 1.27)
				)
				(justify mirror)
			)
		)
		(property "Value" ""
			(at 0 0 90)
			(layer "B.Fab")
			(effects
				(font
					(size 1.27 1.27)
				)
				(justify mirror)
			)
		)
		(duplicate_pad_numbers_are_jumpers no)
		(fp_line
			(start 0.7874 -0.4064)
			(end -0.7874 -0.4064)
			(stroke
				(width 0.1524)
				(type default)
			)
			(layer "B.SilkS")
		)
		(fp_line
			(start -0.7874 -0.4064)
			(end -0.7874 0.4064)
			(stroke
				(width 0.1524)
				(type default)
			)
			(layer "B.SilkS")
		)
		(fp_line
			(start 0.7874 0.4064)
			(end 0.7874 -0.4064)
			(stroke
				(width 0.1524)
				(type default)
			)
			(layer "B.SilkS")
		)
		(fp_line
			(start -0.7874 0.4064)
			(end 0.7874 0.4064)
			(stroke
				(width 0.1524)
				(type default)
			)
			(layer "B.SilkS")
		)
		(fp_line
			(start 0.67945 -0.305054)
			(end 0.12065 -0.305054)
			(stroke
				(width 0.1)
				(type default)
			)
			(layer "B.Fab")
		)
		(fp_line
			(start 0.12065 -0.305054)
			(end 0.12065 -0.2794)
			(stroke
				(width 0.1)
				(type default)
			)
			(layer "B.Fab")
		)
		(fp_line
			(start -0.12065 -0.3048)
			(end -0.67945 -0.3048)
			(stroke
				(width 0.1)
				(type default)
			)
			(layer "B.Fab")
		)
		(fp_line
			(start -0.67945 -0.3048)
			(end -0.67945 0.3048)
			(stroke
				(width 0.1)
				(type default)
			)
			(layer "B.Fab")
		)
		(fp_line
			(start 0.12065 -0.2794)
			(end -0.12065 -0.2794)
			(stroke
				(width 0.1)
				(type default)
			)
			(layer "B.Fab")
		)
		(fp_line
			(start -0.12065 -0.2794)
			(end -0.12065 -0.3048)
			(stroke
				(width 0.1)
				(type default)
			)
			(layer "B.Fab")
		)
		(fp_line
			(start 0.12065 0.2794)
			(end 0.12065 0.3048)
			(stroke
				(width 0.1)
				(type default)
			)
			(layer "B.Fab")
		)
		(fp_line
			(start -0.120396 0.2794)
			(end 0.12065 0.2794)
			(stroke
				(width 0.1)
				(type default)
			)
			(layer "B.Fab")
		)
		(fp_line
			(start 0.67945 0.3048)
			(end 0.67945 -0.305054)
			(stroke
				(width 0.1)
				(type default)
			)
			(layer "B.Fab")
		)
		(fp_line
			(start 0.12065 0.3048)
			(end 0.67945 0.3048)
			(stroke
				(width 0.1)
				(type default)
			)
			(layer "B.Fab")
		)
		(fp_line
			(start -0.120396 0.3048)
			(end -0.120396 0.2794)
			(stroke
				(width 0.1)
				(type default)
			)
			(layer "B.Fab")
		)
		(fp_line
			(start -0.67945 0.3048)
			(end -0.120396 0.3048)
			(stroke
				(width 0.1)
				(type default)
			)
			(layer "B.Fab")
		)
		(pad "1" smd circle
			(at 0.40005 0 270)
			(size 0 0)
			(layers "B.Cu" "B.Mask" "B.Paste")
			(net "PGPPA_AUX")
		)
		(pad "2" smd circle
			(at -0.40005 0 270)
			(size 0 0)
			(layers "B.Cu" "B.Mask" "B.Paste")
			(net "FM_LPC_ESPI_SEL")
		)
	)
	(footprint ""
		(layer "B.Cu")
		(at 66.162174 -16.37157)
		(property "Reference" "C1832"
			(at 0 0 0)
			(layer "B.SilkS")
			(hide yes)
			(effects
				(font
					(size 1.27 1.27)
				)
				(justify mirror)
			)
		)
		(property "Value" ""
			(at 0 0 0)
			(layer "B.Fab")
			(effects
				(font
					(size 1.27 1.27)
				)
				(justify mirror)
			)
		)
		(duplicate_pad_numbers_are_jumpers no)
		(fp_line
			(start -0.7874 -0.4064)
			(end -0.7874 0.4064)
			(stroke
				(width 0.1524)
				(type default)
			)
			(layer "B.SilkS")
		)
		(fp_line
			(start -0.7874 0.4064)
			(end 0.7874 0.4064)
			(stroke
				(width 0.1524)
				(type default)
			)
			(layer "B.SilkS")
		)
		(fp_line
			(start 0.7874 -0.4064)
			(end -0.7874 -0.4064)
			(stroke
				(width 0.1524)
				(type default)
			)
			(layer "B.SilkS")
		)
		(fp_line
			(start 0.7874 0.4064)
			(end 0.7874 -0.4064)
			(stroke
				(width 0.1524)
				(type default)
			)
			(layer "B.SilkS")
		)
		(fp_line
			(start -0.67945 -0.3048)
			(end -0.67945 0.3048)
			(stroke
				(width 0.1)
				(type default)
			)
			(layer "B.Fab")
		)
		(fp_line
			(start -0.67945 0.3048)
			(end -0.120396 0.3048)
			(stroke
				(width 0.1)
				(type default)
			)
			(layer "B.Fab")
		)
		(fp_line
			(start -0.12065 -0.3048)
			(end -0.67945 -0.3048)
			(stroke
				(width 0.1)
				(type default)
			)
			(layer "B.Fab")
		)
		(fp_line
			(start -0.12065 -0.2794)
			(end -0.12065 -0.3048)
			(stroke
				(width 0.1)
				(type default)
			)
			(layer "B.Fab")
		)
		(fp_line
			(start -0.120396 0.2794)
			(end 0.12065 0.2794)
			(stroke
				(width 0.1)
				(type default)
			)
			(layer "B.Fab")
		)
		(fp_line
			(start -0.120396 0.3048)
			(end -0.120396 0.2794)
			(stroke
				(width 0.1)
				(type default)
			)
			(layer "B.Fab")
		)
		(fp_line
			(start 0.12065 -0.305054)
			(end 0.12065 -0.2794)
			(stroke
				(width 0.1)
				(type default)
			)
			(layer "B.Fab")
		)
		(fp_line
			(start 0.12065 -0.2794)
			(end -0.12065 -0.2794)
			(stroke
				(width 0.1)
				(type default)
			)
			(layer "B.Fab")
		)
		(fp_line
			(start 0.12065 0.2794)
			(end 0.12065 0.3048)
			(stroke
				(width 0.1)
				(type default)
			)
			(layer "B.Fab")
		)
		(fp_line
			(start 0.12065 0.3048)
			(end 0.67945 0.3048)
			(stroke
				(width 0.1)
				(type default)
			)
			(layer "B.Fab")
		)
		(fp_line
			(start 0.67945 -0.305054)
			(end 0.12065 -0.305054)
			(stroke
				(width 0.1)
				(type default)
			)
			(layer "B.Fab")
		)
		(fp_line
			(start 0.67945 0.3048)
			(end 0.67945 -0.305054)
			(stroke
				(width 0.1)
				(type default)
			)
			(layer "B.Fab")
		)
		(pad "1" smd circle
			(at 0.40005 0 180)
			(size 0 0)
			(layers "B.Cu" "B.Mask" "B.Paste")
			(net "P12V_OCP_V3_2")
		)
		(pad "2" smd circle
			(at -0.40005 0 180)
			(size 0 0)
			(layers "B.Cu" "B.Mask" "B.Paste")
			(net "GND")
		)
	)
	(footprint ""
		(layer "B.Cu")
		(at 180.90388 -330.495148 180)
		(property "Reference" "R1933"
			(at 0 0 0)
			(layer "B.SilkS")
			(hide yes)
			(effects
				(font
					(size 1.27 1.27)
				)
				(justify mirror)
			)
		)
		(property "Value" ""
			(at 0 0 0)
			(layer "B.Fab")
			(effects
				(font
					(size 1.27 1.27)
				)
				(justify mirror)
			)
		)
		(duplicate_pad_numbers_are_jumpers no)
		(fp_line
			(start 0.7874 0.4064)
			(end 0.7874 -0.4064)
			(stroke
				(width 0.1524)
				(type default)
			)
			(layer "B.SilkS")
		)
		(fp_line
			(start 0.7874 -0.4064)
			(end -0.7874 -0.4064)
			(stroke
				(width 0.1524)
				(type default)
			)
			(layer "B.SilkS")
		)
		(fp_line
			(start -0.7874 0.4064)
			(end 0.7874 0.4064)
			(stroke
				(width 0.1524)
				(type default)
			)
			(layer "B.SilkS")
		)
		(fp_line
			(start -0.7874 -0.4064)
			(end -0.7874 0.4064)
			(stroke
				(width 0.1524)
				(type default)
			)
			(layer "B.SilkS")
		)
		(fp_line
			(start 0.67945 0.3048)
			(end 0.67945 -0.305054)
			(stroke
				(width 0.1)
				(type default)
			)
			(layer "B.Fab")
		)
		(fp_line
			(start 0.67945 -0.305054)
			(end 0.12065 -0.305054)
			(stroke
				(width 0.1)
				(type default)
			)
			(layer "B.Fab")
		)
		(fp_line
			(start 0.12065 0.3048)
			(end 0.67945 0.3048)
			(stroke
				(width 0.1)
				(type default)
			)
			(layer "B.Fab")
		)
		(fp_line
			(start 0.12065 0.2794)
			(end 0.12065 0.3048)
			(stroke
				(width 0.1)
				(type default)
			)
			(layer "B.Fab")
		)
		(fp_line
			(start 0.12065 -0.2794)
			(end -0.12065 -0.2794)
			(stroke
				(width 0.1)
				(type default)
			)
			(layer "B.Fab")
		)
		(fp_line
			(start 0.12065 -0.305054)
			(end 0.12065 -0.2794)
			(stroke
				(width 0.1)
				(type default)
			)
			(layer "B.Fab")
		)
		(fp_line
			(start -0.120396 0.3048)
			(end -0.120396 0.2794)
			(stroke
				(width 0.1)
				(type default)
			)
			(layer "B.Fab")
		)
		(fp_line
			(start -0.120396 0.2794)
			(end 0.12065 0.2794)
			(stroke
				(width 0.1)
				(type default)
			)
			(layer "B.Fab")
		)
		(fp_line
			(start -0.12065 -0.2794)
			(end -0.12065 -0.3048)
			(stroke
				(width 0.1)
				(type default)
			)
			(layer "B.Fab")
		)
		(fp_line
			(start -0.12065 -0.3048)
			(end -0.67945 -0.3048)
			(stroke
				(width 0.1)
				(type default)
			)
			(layer "B.Fab")
		)
		(fp_line
			(start -0.67945 0.3048)
			(end -0.120396 0.3048)
			(stroke
				(width 0.1)
				(type default)
			)
			(layer "B.Fab")
		)
		(fp_line
			(start -0.67945 -0.3048)
			(end -0.67945 0.3048)
			(stroke
				(width 0.1)
				(type default)
			)
			(layer "B.Fab")
		)
		(pad "1" smd circle
			(at 0.40005 0)
			(size 0 0)
			(layers "B.Cu" "B.Mask" "B.Paste")
			(net "SMB_S3M_CPU0_PIROM_3V3AUX_SDA")
		)
		(pad "2" smd circle
			(at -0.40005 0)
			(size 0 0)
			(layers "B.Cu" "B.Mask" "B.Paste")
			(net "SMB_S3M_CPU0_PIROM_3V3AUX_SDA_1")
		)
	)
	(footprint ""
		(layer "B.Cu")
		(at 377.485402 -329.921616 -90)
		(property "Reference" "PC323"
			(at 0 0 90)
			(layer "B.SilkS")
			(hide yes)
			(effects
				(font
					(size 1.27 1.27)
				)
				(justify mirror)
			)
		)
		(property "Value" ""
			(at 0 0 90)
			(layer "B.Fab")
			(effects
				(font
					(size 1.27 1.27)
				)
				(justify mirror)
			)
		)
		(duplicate_pad_numbers_are_jumpers no)
		(fp_line
			(start -4.533392 2.249932)
			(end 4.533392 2.249932)
			(stroke
				(width 0.1524)
				(type default)
			)
			(layer "B.SilkS")
		)
		(fp_line
			(start 4.533392 2.249932)
			(end 4.533392 -2.249932)
			(stroke
				(width 0.1524)
				(type default)
			)
			(layer "B.SilkS")
		)
		(fp_line
			(start -4.533392 -2.249932)
			(end -4.533392 2.249932)
			(stroke
				(width 0.1524)
				(type default)
			)
			(layer "B.SilkS")
		)
		(fp_line
			(start 4.533392 -2.249932)
			(end -4.533392 -2.249932)
			(stroke
				(width 0.1524)
				(type default)
			)
			(layer "B.SilkS")
		)
		(fp_rect
			(start 5.39242 2.326132)
			(end 4.533392 -2.326132)
			(stroke
				(width 0)
				(type default)
			)
			(fill yes)
			(layer "B.SilkS")
		)
		(fp_line
			(start -3.750056 2.249932)
			(end 3.750056 2.249932)
			(stroke
				(width 0.1)
				(type default)
			)
			(layer "B.Fab")
		)
		(fp_line
			(start 3.750056 2.249932)
			(end 3.750056 -2.249932)
			(stroke
				(width 0.1)
				(type default)
			)
			(layer "B.Fab")
		)
		(fp_line
			(start -3.750056 -2.249932)
			(end -3.750056 2.249932)
			(stroke
				(width 0.1)
				(type default)
			)
			(layer "B.Fab")
		)
		(fp_line
			(start 3.750056 -2.249932)
			(end -3.750056 -2.249932)
			(stroke
				(width 0.1)
				(type default)
			)
			(layer "B.Fab")
		)
		(fp_text user "-"
			(at -4.673092 1.617472 270)
			(unlocked yes)
			(layer "B.SilkS")
			(effects
				(font
					(size 1.905 1.4224)
					(thickness 0.1524)
				)
				(justify left mirror)
			)
		)
		(fp_text user "+"
			(at 6.322314 0.786384 180)
			(unlocked yes)
			(layer "B.SilkS")
			(effects
				(font
					(size 1.905 1.4224)
					(thickness 0.1524)
				)
				(justify left mirror)
			)
		)
		(fp_text user "+"
			(at 6.322314 0.786384 180)
			(unlocked yes)
			(layer "B.Fab")
			(effects
				(font
					(size 1.905 1.4224)
					(thickness 0.1524)
				)
				(justify left mirror)
			)
		)
		(fp_text user "-"
			(at -4.8514 -0.14605 270)
			(unlocked yes)
			(layer "B.Fab")
			(effects
				(font
					(size 1.905 1.4224)
					(thickness 0.1524)
				)
				(justify left mirror)
			)
		)
		(pad "1" smd rect
			(at 3.199892 0 90)
			(size 2.413 2.8194)
			(layers "B.Cu" "B.Mask" "B.Paste")
			(net "PVCCIN_CPU0")
		)
		(pad "2" smd rect
			(at -3.199892 0 90)
			(size 2.413 2.8194)
			(layers "B.Cu" "B.Mask" "B.Paste")
			(net "GND")
		)
	)
)
